(kicad_pcb
	(version 20260206)
	(generator "pcbnew")
	(generator_version "10.0")
	(general
		(thickness 1.6)
		(legacy_teardrops no)
	)
	(paper "A4")
	(title_block
		(title "04192023_DAF0TMB3IC0_F0TG_MB_C_brd_V02_OCP.brd")
		(comment 1 "Grand Teton / footprint 2335 of 8354 (J69), pads 114-226 of 291")
	)
	(layers
		(0 "F.Cu" signal "TOP")
		(4 "In1.Cu" signal "GND")
		(6 "In2.Cu" signal "IN1")
		(8 "In3.Cu" signal "GND1")
		(10 "In4.Cu" signal "IN2")
		(12 "In5.Cu" signal "GND2")
		(14 "In6.Cu" signal "IN3")
		(16 "In7.Cu" signal "GND3")
		(18 "In8.Cu" signal "VCC")
		(20 "In9.Cu" signal "VCC1")
		(22 "In10.Cu" signal "GND4")
		(24 "In11.Cu" signal "IN4")
		(26 "In12.Cu" signal "GND5")
		(28 "In13.Cu" signal "IN5")
		(30 "In14.Cu" signal "GND6")
		(32 "In15.Cu" signal "IN6")
		(34 "In16.Cu" signal "GND7")
		(2 "B.Cu" signal "BOTTOM")
		(9 "F.Adhes" user "F.Adhesive")
		(11 "B.Adhes" user "B.Adhesive")
		(13 "F.Paste" user "Package Geometry/Pastemask Top")
		(15 "B.Paste" user "Package Geometry/Pastemask Bottom")
		(5 "F.SilkS" user "Ref Des/Silkscreen Top")
		(7 "B.SilkS" user "Ref Des/Silkscreen Bottom")
		(1 "F.Mask" user "Board Geometry/Soldermask Top")
		(3 "B.Mask" user "Board Geometry/Soldermask Bottom")
		(17 "Dwgs.User" user "User.Drawings")
		(19 "Cmts.User" user "User.Comments")
		(21 "Eco1.User" user "User.Eco1")
		(23 "Eco2.User" user "User.Eco2")
		(25 "Edge.Cuts" user "Board Geometry/Outline")
		(27 "Margin" user)
		(31 "F.CrtYd" user "Package Geometry/Place Bound Top")
		(29 "B.CrtYd" user "Package Geometry/Place Bound Bottom")
		(35 "F.Fab" user "Ref Des/Assembly Top")
		(33 "B.Fab" user "Ref Des/Assembly Bottom")
	)
	(footprint ""
		(layer "F.Cu")
		(at 421.962072 -255.560068 180)
		(property "Reference" "J69"
			(at 3.448304 81.947512 0)
			(unlocked yes)
			(layer "F.SilkS")
			(effects
				(font
					(size 0.7874 0.5842)
					(thickness 0.1524)
				)
			)
		)
		(property "Value" ""
			(at 0 0 180)
			(layer "F.Fab")
			(effects
				(font
					(size 1.27 1.27)
				)
			)
		)
		(duplicate_pad_numbers_are_jumpers no)
		(pad "114" smd rect
			(at -2.050034 37.824918 90)
			(size 0.519938 1.4986)
			(layers "F.Cu" "F.Mask" "F.Paste")
			(net "GND")
		)
		(pad "115" smd rect
			(at -2.050034 38.675056 90)
			(size 0.519938 1.4986)
			(layers "F.Cu" "F.Mask" "F.Paste")
			(net "M_H_CPU0_SB_DQS_DP<1>")
		)
		(pad "116" smd rect
			(at -2.050034 39.52494 90)
			(size 0.519938 1.4986)
			(layers "F.Cu" "F.Mask" "F.Paste")
			(net "M_H_CPU0_SB_DQS_DN<1>")
		)
		(pad "117" smd rect
			(at -2.050034 40.375078 90)
			(size 0.519938 1.4986)
			(layers "F.Cu" "F.Mask" "F.Paste")
			(net "GND")
		)
		(pad "118" smd rect
			(at -2.050034 41.224962 90)
			(size 0.519938 1.4986)
			(layers "F.Cu" "F.Mask" "F.Paste")
			(net "M_H_CPU0_SB_DQ<12>")
		)
		(pad "119" smd rect
			(at -2.050034 42.0751 90)
			(size 0.519938 1.4986)
			(layers "F.Cu" "F.Mask" "F.Paste")
			(net "GND")
		)
		(pad "120" smd rect
			(at -2.050034 42.924984 90)
			(size 0.519938 1.4986)
			(layers "F.Cu" "F.Mask" "F.Paste")
			(net "M_H_CPU0_SB_DQ<13>")
		)
		(pad "121" smd rect
			(at -2.050034 43.775122 90)
			(size 0.519938 1.4986)
			(layers "F.Cu" "F.Mask" "F.Paste")
			(net "GND")
		)
		(pad "122" smd rect
			(at -2.050034 44.625006 90)
			(size 0.519938 1.4986)
			(layers "F.Cu" "F.Mask" "F.Paste")
			(net "M_H_CPU0_SB_DQ<16>")
		)
		(pad "123" smd rect
			(at -2.050034 45.47489 90)
			(size 0.519938 1.4986)
			(layers "F.Cu" "F.Mask" "F.Paste")
			(net "GND")
		)
		(pad "124" smd rect
			(at -2.050034 46.325028 90)
			(size 0.519938 1.4986)
			(layers "F.Cu" "F.Mask" "F.Paste")
			(net "M_H_CPU0_SB_DQ<17>")
		)
		(pad "125" smd rect
			(at -2.050034 47.174912 90)
			(size 0.519938 1.4986)
			(layers "F.Cu" "F.Mask" "F.Paste")
			(net "GND")
		)
		(pad "126" smd rect
			(at -2.050034 48.02505 90)
			(size 0.519938 1.4986)
			(layers "F.Cu" "F.Mask" "F.Paste")
			(net "M_H_CPU0_SB_DQS_DP<2>")
		)
		(pad "127" smd rect
			(at -2.050034 48.874934 90)
			(size 0.519938 1.4986)
			(layers "F.Cu" "F.Mask" "F.Paste")
			(net "M_H_CPU0_SB_DQS_DN<2>")
		)
		(pad "128" smd rect
			(at -2.050034 49.725072 90)
			(size 0.519938 1.4986)
			(layers "F.Cu" "F.Mask" "F.Paste")
			(net "GND")
		)
		(pad "129" smd rect
			(at -2.050034 50.574956 90)
			(size 0.519938 1.4986)
			(layers "F.Cu" "F.Mask" "F.Paste")
			(net "M_H_CPU0_SB_DQ<20>")
		)
		(pad "130" smd rect
			(at -2.050034 51.425094 90)
			(size 0.519938 1.4986)
			(layers "F.Cu" "F.Mask" "F.Paste")
			(net "GND")
		)
		(pad "131" smd rect
			(at -2.050034 52.274978 90)
			(size 0.519938 1.4986)
			(layers "F.Cu" "F.Mask" "F.Paste")
			(net "M_H_CPU0_SB_DQ<21>")
		)
		(pad "132" smd rect
			(at -2.050034 53.125116 90)
			(size 0.519938 1.4986)
			(layers "F.Cu" "F.Mask" "F.Paste")
			(net "GND")
		)
		(pad "133" smd rect
			(at -2.050034 53.975 90)
			(size 0.519938 1.4986)
			(layers "F.Cu" "F.Mask" "F.Paste")
			(net "M_H_CPU0_SB_DQ<24>")
		)
		(pad "134" smd rect
			(at -2.050034 54.824884 90)
			(size 0.519938 1.4986)
			(layers "F.Cu" "F.Mask" "F.Paste")
			(net "GND")
		)
		(pad "135" smd rect
			(at -2.050034 55.675022 90)
			(size 0.519938 1.4986)
			(layers "F.Cu" "F.Mask" "F.Paste")
			(net "M_H_CPU0_SB_DQ<25>")
		)
		(pad "136" smd rect
			(at -2.050034 56.524906 90)
			(size 0.519938 1.4986)
			(layers "F.Cu" "F.Mask" "F.Paste")
			(net "GND")
		)
		(pad "137" smd rect
			(at -2.050034 57.375044 90)
			(size 0.519938 1.4986)
			(layers "F.Cu" "F.Mask" "F.Paste")
			(net "M_H_CPU0_SB_DQS_DP<3>")
		)
		(pad "138" smd rect
			(at -2.050034 58.224928 90)
			(size 0.519938 1.4986)
			(layers "F.Cu" "F.Mask" "F.Paste")
			(net "M_H_CPU0_SB_DQS_DN<3>")
		)
		(pad "139" smd rect
			(at -2.050034 59.075066 90)
			(size 0.519938 1.4986)
			(layers "F.Cu" "F.Mask" "F.Paste")
			(net "GND")
		)
		(pad "140" smd rect
			(at -2.050034 59.92495 90)
			(size 0.519938 1.4986)
			(layers "F.Cu" "F.Mask" "F.Paste")
			(net "M_H_CPU0_SB_DQ<28>")
		)
		(pad "141" smd rect
			(at -2.050034 60.775088 90)
			(size 0.519938 1.4986)
			(layers "F.Cu" "F.Mask" "F.Paste")
			(net "GND")
		)
		(pad "142" smd rect
			(at -2.050034 61.624972 90)
			(size 0.519938 1.4986)
			(layers "F.Cu" "F.Mask" "F.Paste")
			(net "M_H_CPU0_SB_DQ<29>")
		)
		(pad "143" smd rect
			(at -2.050034 62.47511 90)
			(size 0.519938 1.4986)
			(layers "F.Cu" "F.Mask" "F.Paste")
			(net "GND")
		)
		(pad "144" smd rect
			(at -2.050034 63.324994 90)
			(size 0.519938 1.4986)
			(layers "F.Cu" "F.Mask" "F.Paste")
			(net "Net_2348")
		)
		(pad "145" smd rect
			(at 2.050034 -63.324994 90)
			(size 0.519938 1.4986)
			(layers "F.Cu" "F.Mask" "F.Paste")
			(net "P12V_MEM_CPU0")
		)
		(pad "146" smd rect
			(at 2.050034 -62.47511 90)
			(size 0.519938 1.4986)
			(layers "F.Cu" "F.Mask" "F.Paste")
			(net "P12V_MEM_CPU0")
		)
		(pad "147" smd rect
			(at 2.050034 -61.624972 90)
			(size 0.519938 1.4986)
			(layers "F.Cu" "F.Mask" "F.Paste")
			(net "PWRGD_CHH_CPU0_DIMM")
		)
		(pad "148" smd rect
			(at 2.050034 -60.775088 90)
			(size 0.519938 1.4986)
			(layers "F.Cu" "F.Mask" "F.Paste")
			(net "PD_CHH_CPU0_DIMM_SAA")
		)
		(pad "149" smd rect
			(at 2.050034 -59.92495 90)
			(size 0.519938 1.4986)
			(layers "F.Cu" "F.Mask" "F.Paste")
			(net "Net_2349")
		)
		(pad "150" smd rect
			(at 2.050034 -59.075066 90)
			(size 0.519938 1.4986)
			(layers "F.Cu" "F.Mask" "F.Paste")
			(net "Net_2350")
		)
		(pad "151" smd rect
			(at 2.050034 -58.224928 90)
			(size 0.519938 1.4986)
			(layers "F.Cu" "F.Mask" "F.Paste")
			(net "GND")
		)
		(pad "152" smd rect
			(at 2.050034 -57.375044 90)
			(size 0.519938 1.4986)
			(layers "F.Cu" "F.Mask" "F.Paste")
			(net "M_H_CPU0_SA_DQ<2>")
		)
		(pad "153" smd rect
			(at 2.050034 -56.524906 90)
			(size 0.519938 1.4986)
			(layers "F.Cu" "F.Mask" "F.Paste")
			(net "GND")
		)
		(pad "154" smd rect
			(at 2.050034 -55.675022 90)
			(size 0.519938 1.4986)
			(layers "F.Cu" "F.Mask" "F.Paste")
			(net "M_H_CPU0_SA_DQ<3>")
		)
		(pad "155" smd rect
			(at 2.050034 -54.824884 90)
			(size 0.519938 1.4986)
			(layers "F.Cu" "F.Mask" "F.Paste")
			(net "GND")
		)
		(pad "156" smd rect
			(at 2.050034 -53.975 90)
			(size 0.519938 1.4986)
			(layers "F.Cu" "F.Mask" "F.Paste")
			(net "M_H_CPU0_SA_DQS_DN<5>")
		)
		(pad "157" smd rect
			(at 2.050034 -53.125116 90)
			(size 0.519938 1.4986)
			(layers "F.Cu" "F.Mask" "F.Paste")
			(net "M_H_CPU0_SA_DQS_DP<5>")
		)
		(pad "158" smd rect
			(at 2.050034 -52.274978 90)
			(size 0.519938 1.4986)
			(layers "F.Cu" "F.Mask" "F.Paste")
			(net "GND")
		)
		(pad "159" smd rect
			(at 2.050034 -51.425094 90)
			(size 0.519938 1.4986)
			(layers "F.Cu" "F.Mask" "F.Paste")
			(net "M_H_CPU0_SA_DQ<6>")
		)
		(pad "160" smd rect
			(at 2.050034 -50.574956 90)
			(size 0.519938 1.4986)
			(layers "F.Cu" "F.Mask" "F.Paste")
			(net "GND")
		)
		(pad "161" smd rect
			(at 2.050034 -49.725072 90)
			(size 0.519938 1.4986)
			(layers "F.Cu" "F.Mask" "F.Paste")
			(net "M_H_CPU0_SA_DQ<7>")
		)
		(pad "162" smd rect
			(at 2.050034 -48.874934 90)
			(size 0.519938 1.4986)
			(layers "F.Cu" "F.Mask" "F.Paste")
			(net "GND")
		)
		(pad "163" smd rect
			(at 2.050034 -48.02505 90)
			(size 0.519938 1.4986)
			(layers "F.Cu" "F.Mask" "F.Paste")
			(net "M_H_CPU0_SA_DQ<10>")
		)
		(pad "164" smd rect
			(at 2.050034 -47.174912 90)
			(size 0.519938 1.4986)
			(layers "F.Cu" "F.Mask" "F.Paste")
			(net "GND")
		)
		(pad "165" smd rect
			(at 2.050034 -46.325028 90)
			(size 0.519938 1.4986)
			(layers "F.Cu" "F.Mask" "F.Paste")
			(net "M_H_CPU0_SA_DQ<11>")
		)
		(pad "166" smd rect
			(at 2.050034 -45.47489 90)
			(size 0.519938 1.4986)
			(layers "F.Cu" "F.Mask" "F.Paste")
			(net "GND")
		)
		(pad "167" smd rect
			(at 2.050034 -44.625006 90)
			(size 0.519938 1.4986)
			(layers "F.Cu" "F.Mask" "F.Paste")
			(net "M_H_CPU0_SA_DQS_DN<6>")
		)
		(pad "168" smd rect
			(at 2.050034 -43.775122 90)
			(size 0.519938 1.4986)
			(layers "F.Cu" "F.Mask" "F.Paste")
			(net "M_H_CPU0_SA_DQS_DP<6>")
		)
		(pad "169" smd rect
			(at 2.050034 -42.924984 90)
			(size 0.519938 1.4986)
			(layers "F.Cu" "F.Mask" "F.Paste")
			(net "GND")
		)
		(pad "170" smd rect
			(at 2.050034 -42.0751 90)
			(size 0.519938 1.4986)
			(layers "F.Cu" "F.Mask" "F.Paste")
			(net "M_H_CPU0_SA_DQ<14>")
		)
		(pad "171" smd rect
			(at 2.050034 -41.224962 90)
			(size 0.519938 1.4986)
			(layers "F.Cu" "F.Mask" "F.Paste")
			(net "GND")
		)
		(pad "172" smd rect
			(at 2.050034 -40.375078 90)
			(size 0.519938 1.4986)
			(layers "F.Cu" "F.Mask" "F.Paste")
			(net "M_H_CPU0_SA_DQ<15>")
		)
		(pad "173" smd rect
			(at 2.050034 -39.52494 90)
			(size 0.519938 1.4986)
			(layers "F.Cu" "F.Mask" "F.Paste")
			(net "GND")
		)
		(pad "174" smd rect
			(at 2.050034 -38.675056 90)
			(size 0.519938 1.4986)
			(layers "F.Cu" "F.Mask" "F.Paste")
			(net "M_H_CPU0_SA_DQ<18>")
		)
		(pad "175" smd rect
			(at 2.050034 -37.824918 90)
			(size 0.519938 1.4986)
			(layers "F.Cu" "F.Mask" "F.Paste")
			(net "GND")
		)
		(pad "176" smd rect
			(at 2.050034 -36.975034 90)
			(size 0.519938 1.4986)
			(layers "F.Cu" "F.Mask" "F.Paste")
			(net "M_H_CPU0_SA_DQ<19>")
		)
		(pad "177" smd rect
			(at 2.050034 -36.124896 90)
			(size 0.519938 1.4986)
			(layers "F.Cu" "F.Mask" "F.Paste")
			(net "GND")
		)
		(pad "178" smd rect
			(at 2.050034 -35.275012 90)
			(size 0.519938 1.4986)
			(layers "F.Cu" "F.Mask" "F.Paste")
			(net "M_H_CPU0_SA_DQS_DN<7>")
		)
		(pad "179" smd rect
			(at 2.050034 -34.425128 90)
			(size 0.519938 1.4986)
			(layers "F.Cu" "F.Mask" "F.Paste")
			(net "M_H_CPU0_SA_DQS_DP<7>")
		)
		(pad "180" smd rect
			(at 2.050034 -33.57499 90)
			(size 0.519938 1.4986)
			(layers "F.Cu" "F.Mask" "F.Paste")
			(net "GND")
		)
		(pad "181" smd rect
			(at 2.050034 -32.725106 90)
			(size 0.519938 1.4986)
			(layers "F.Cu" "F.Mask" "F.Paste")
			(net "M_H_CPU0_SA_DQ<22>")
		)
		(pad "182" smd rect
			(at 2.050034 -31.874968 90)
			(size 0.519938 1.4986)
			(layers "F.Cu" "F.Mask" "F.Paste")
			(net "GND")
		)
		(pad "183" smd rect
			(at 2.050034 -31.025084 90)
			(size 0.519938 1.4986)
			(layers "F.Cu" "F.Mask" "F.Paste")
			(net "M_H_CPU0_SA_DQ<23>")
		)
		(pad "184" smd rect
			(at 2.050034 -30.174946 90)
			(size 0.519938 1.4986)
			(layers "F.Cu" "F.Mask" "F.Paste")
			(net "GND")
		)
		(pad "185" smd rect
			(at 2.050034 -29.325062 90)
			(size 0.519938 1.4986)
			(layers "F.Cu" "F.Mask" "F.Paste")
			(net "M_H_CPU0_SA_DQ<26>")
		)
		(pad "186" smd rect
			(at 2.050034 -28.474924 90)
			(size 0.519938 1.4986)
			(layers "F.Cu" "F.Mask" "F.Paste")
			(net "GND")
		)
		(pad "187" smd rect
			(at 2.050034 -27.62504 90)
			(size 0.519938 1.4986)
			(layers "F.Cu" "F.Mask" "F.Paste")
			(net "M_H_CPU0_SA_DQ<27>")
		)
		(pad "188" smd rect
			(at 2.050034 -26.774902 90)
			(size 0.519938 1.4986)
			(layers "F.Cu" "F.Mask" "F.Paste")
			(net "GND")
		)
		(pad "189" smd rect
			(at 2.050034 -25.925018 90)
			(size 0.519938 1.4986)
			(layers "F.Cu" "F.Mask" "F.Paste")
			(net "M_H_CPU0_SA_DQS_DN<8>")
		)
		(pad "190" smd rect
			(at 2.050034 -25.07488 90)
			(size 0.519938 1.4986)
			(layers "F.Cu" "F.Mask" "F.Paste")
			(net "M_H_CPU0_SA_DQS_DP<8>")
		)
		(pad "191" smd rect
			(at 2.050034 -24.224996 90)
			(size 0.519938 1.4986)
			(layers "F.Cu" "F.Mask" "F.Paste")
			(net "GND")
		)
		(pad "192" smd rect
			(at 2.050034 -23.375112 90)
			(size 0.519938 1.4986)
			(layers "F.Cu" "F.Mask" "F.Paste")
			(net "M_H_CPU0_SA_DQ<30>")
		)
		(pad "193" smd rect
			(at 2.050034 -22.524974 90)
			(size 0.519938 1.4986)
			(layers "F.Cu" "F.Mask" "F.Paste")
			(net "GND")
		)
		(pad "194" smd rect
			(at 2.050034 -21.67509 90)
			(size 0.519938 1.4986)
			(layers "F.Cu" "F.Mask" "F.Paste")
			(net "M_H_CPU0_SA_DQ<31>")
		)
		(pad "195" smd rect
			(at 2.050034 -20.824952 90)
			(size 0.519938 1.4986)
			(layers "F.Cu" "F.Mask" "F.Paste")
			(net "GND")
		)
		(pad "196" smd rect
			(at 2.050034 -19.975068 90)
			(size 0.519938 1.4986)
			(layers "F.Cu" "F.Mask" "F.Paste")
			(net "M_H_CPU0_SA_CB<2>")
		)
		(pad "197" smd rect
			(at 2.050034 -19.12493 90)
			(size 0.519938 1.4986)
			(layers "F.Cu" "F.Mask" "F.Paste")
			(net "GND")
		)
		(pad "198" smd rect
			(at 2.050034 -18.275046 90)
			(size 0.519938 1.4986)
			(layers "F.Cu" "F.Mask" "F.Paste")
			(net "M_H_CPU0_SA_CB<3>")
		)
		(pad "199" smd rect
			(at 2.050034 -17.424908 90)
			(size 0.519938 1.4986)
			(layers "F.Cu" "F.Mask" "F.Paste")
			(net "GND")
		)
		(pad "200" smd rect
			(at 2.050034 -16.575024 90)
			(size 0.519938 1.4986)
			(layers "F.Cu" "F.Mask" "F.Paste")
			(net "M_H_CPU0_SA_DQS_DN<9>")
		)
		(pad "201" smd rect
			(at 2.050034 -15.724886 90)
			(size 0.519938 1.4986)
			(layers "F.Cu" "F.Mask" "F.Paste")
			(net "M_H_CPU0_SA_DQS_DP<9>")
		)
		(pad "202" smd rect
			(at 2.050034 -14.875002 90)
			(size 0.519938 1.4986)
			(layers "F.Cu" "F.Mask" "F.Paste")
			(net "GND")
		)
		(pad "203" smd rect
			(at 2.050034 -14.025118 90)
			(size 0.519938 1.4986)
			(layers "F.Cu" "F.Mask" "F.Paste")
			(net "M_H_CPU0_SA_CB<6>")
		)
		(pad "204" smd rect
			(at 2.050034 -13.17498 90)
			(size 0.519938 1.4986)
			(layers "F.Cu" "F.Mask" "F.Paste")
			(net "GND")
		)
		(pad "205" smd rect
			(at 2.050034 -12.325096 90)
			(size 0.519938 1.4986)
			(layers "F.Cu" "F.Mask" "F.Paste")
			(net "M_H_CPU0_SA_CB<7>")
		)
		(pad "206" smd rect
			(at 2.050034 -11.474958 90)
			(size 0.519938 1.4986)
			(layers "F.Cu" "F.Mask" "F.Paste")
			(net "GND")
		)
		(pad "207" smd rect
			(at 2.050034 -10.625074 90)
			(size 0.519938 1.4986)
			(layers "F.Cu" "F.Mask" "F.Paste")
			(net "M_H_CPU0_RESET_N")
		)
		(pad "208" smd rect
			(at 2.050034 -9.774936 90)
			(size 0.519938 1.4986)
			(layers "F.Cu" "F.Mask" "F.Paste")
			(net "GND")
		)
		(pad "209" smd rect
			(at 2.050034 -8.925052 90)
			(size 0.519938 1.4986)
			(layers "F.Cu" "F.Mask" "F.Paste")
			(net "M_H_CPU0_SA_CS_N<1>")
		)
		(pad "210" smd rect
			(at 2.050034 -8.074914 90)
			(size 0.519938 1.4986)
			(layers "F.Cu" "F.Mask" "F.Paste")
			(net "GND")
		)
		(pad "211" smd rect
			(at 2.050034 -7.22503 90)
			(size 0.519938 1.4986)
			(layers "F.Cu" "F.Mask" "F.Paste")
			(net "M_H_CPU0_SA_CA<1>")
		)
		(pad "212" smd rect
			(at 2.050034 -6.374892 90)
			(size 0.519938 1.4986)
			(layers "F.Cu" "F.Mask" "F.Paste")
			(net "GND")
		)
		(pad "213" smd rect
			(at 2.050034 -5.525008 90)
			(size 0.519938 1.4986)
			(layers "F.Cu" "F.Mask" "F.Paste")
			(net "M_H_CPU0_SA_CA<3>")
		)
		(pad "214" smd rect
			(at 2.050034 -4.675124 90)
			(size 0.519938 1.4986)
			(layers "F.Cu" "F.Mask" "F.Paste")
			(net "GND")
		)
		(pad "215" smd rect
			(at 2.050034 -3.824986 90)
			(size 0.519938 1.4986)
			(layers "F.Cu" "F.Mask" "F.Paste")
			(net "M_H_CPU0_SA_CA<5>")
		)
		(pad "216" smd rect
			(at 2.050034 -2.975102 90)
			(size 0.519938 1.4986)
			(layers "F.Cu" "F.Mask" "F.Paste")
			(net "GND")
		)
		(pad "217" smd rect
			(at 2.050034 -2.124964 90)
			(size 0.519938 1.4986)
			(layers "F.Cu" "F.Mask" "F.Paste")
			(net "M_H_CPU0_CLK_DP<0>")
		)
		(pad "218" smd rect
			(at 2.050034 -1.27508 90)
			(size 0.519938 1.4986)
			(layers "F.Cu" "F.Mask" "F.Paste")
			(net "M_H_CPU0_CLK_DN<0>")
		)
		(pad "219" smd rect
			(at 2.050034 -0.424942 90)
			(size 0.519938 1.4986)
			(layers "F.Cu" "F.Mask" "F.Paste")
			(net "GND")
		)
		(pad "220" smd rect
			(at 2.050034 5.525008 90)
			(size 0.519938 1.4986)
			(layers "F.Cu" "F.Mask" "F.Paste")
			(net "Net_2351")
		)
		(pad "221" smd rect
			(at 2.050034 6.374892 90)
			(size 0.519938 1.4986)
			(layers "F.Cu" "F.Mask" "F.Paste")
			(net "M_H_CPU0_SB_CA<1>")
		)
		(pad "222" smd rect
			(at 2.050034 7.22503 90)
			(size 0.519938 1.4986)
			(layers "F.Cu" "F.Mask" "F.Paste")
			(net "GND")
		)
		(pad "223" smd rect
			(at 2.050034 8.074914 90)
			(size 0.519938 1.4986)
			(layers "F.Cu" "F.Mask" "F.Paste")
			(net "M_H_CPU0_SB_CA<3>")
		)
		(pad "224" smd rect
			(at 2.050034 8.925052 90)
			(size 0.519938 1.4986)
			(layers "F.Cu" "F.Mask" "F.Paste")
			(net "GND")
		)
		(pad "225" smd rect
			(at 2.050034 9.774936 90)
			(size 0.519938 1.4986)
			(layers "F.Cu" "F.Mask" "F.Paste")
			(net "M_H_CPU0_SB_CA<5>")
		)
		(pad "226" smd rect
			(at 2.050034 10.625074 90)
			(size 0.519938 1.4986)
			(layers "F.Cu" "F.Mask" "F.Paste")
			(net "GND")
		)
	)
)
